# BASEBOARD_FAB2 (Tioga Pass) — schematic netlist excerpt (pin names and nets, part order shuffled) for the footprints in the layout excerpt that follows; sources: Cadence DE-HDL packaged netlist, KiCad conversion of Wiwynn_Tioga_Pass_MB.brd

R6W45  RES  4.75K 1% CHIP  pkg 0402  page 164 : A = PCA9554_A2 ; B = GND
R4A3  RES  0.0 5% CHIP  pkg 0402  page 230 : A = PWRGD_PVDDQ_KLM_R ; B = FM_PVTT_KLM_EN_R
R7C14  RES  33.2 1% CHIP  pkg 0402  page 121 : A = RMII_BMC_PCH_SPRNGVLLE_RXER ; B = RMII_BMC_PCH_SPRNGVLLE_RXER_R

(kicad_pcb
	(version 20260206)
	(generator "pcbnew")
	(generator_version "10.0")
	(general
		(thickness 1.6)
		(legacy_teardrops no)
	)
	(paper "A4")
	(title_block
		(title "Wiwynn_Tioga_Pass_MB.brd")
		(comment 1 "Tioga Pass / footprints 1196-1198 of 4770")
	)
	(layers
		(0 "F.Cu" signal "TOP")
		(4 "In1.Cu" signal "L2GND")
		(6 "In2.Cu" signal "L3")
		(8 "In3.Cu" signal "L4GND")
		(10 "In4.Cu" signal "L5")
		(12 "In5.Cu" signal "L6GND")
		(14 "In6.Cu" signal "L7VCC")
		(16 "In7.Cu" signal "L8VCC")
		(18 "In8.Cu" signal "L9GND")
		(20 "In9.Cu" signal "L10")
		(22 "In10.Cu" signal "L11GND")
		(24 "In11.Cu" signal "L12")
		(26 "In12.Cu" signal "L13GND")
		(2 "B.Cu" signal "BOTTOM")
		(9 "F.Adhes" user "F.Adhesive")
		(11 "B.Adhes" user "B.Adhesive")
		(13 "F.Paste" user "Package Geometry/Pastemask Top")
		(15 "B.Paste" user "Package Geometry/Pastemask Bottom")
		(5 "F.SilkS" user "Ref Des/Silkscreen Top")
		(7 "B.SilkS" user "Ref Des/Silkscreen Bottom")
		(1 "F.Mask" user "Board Geometry/Soldermask Top")
		(3 "B.Mask" user "Board Geometry/Soldermask Bottom")
		(17 "Dwgs.User" user "User.Drawings")
		(19 "Cmts.User" user "User.Comments")
		(21 "Eco1.User" user "User.Eco1")
		(23 "Eco2.User" user "User.Eco2")
		(25 "Edge.Cuts" user "Board Geometry/Outline")
		(27 "Margin" user)
		(31 "F.CrtYd" user "Package Geometry/Place Bound Top")
		(29 "B.CrtYd" user "Package Geometry/Place Bound Bottom")
		(35 "F.Fab" user "Ref Des/Assembly Top")
		(33 "B.Fab" user "Ref Des/Assembly Bottom")
	)
	(footprint ""
		(layer "F.Cu")
		(at 433.07 -15.113)
		(property "Reference" "R6W45"
			(at -0.8382 -0.67818 0)
			(unlocked yes)
			(layer "F.SilkS")
			(effects
				(font
					(size 0.4064 0.254)
					(thickness 0.1524)
				)
				(justify left)
			)
		)
		(property "Value" ""
			(at 0 0 0)
			(layer "F.Fab")
			(effects
				(font
					(size 1.27 1.27)
				)
			)
		)
		(duplicate_pad_numbers_are_jumpers no)
		(fp_poly
			(pts
				(xy -0.2794 -0.1016) (xy 0.2794 -0.1016) (xy 0.2794 0.9906) (xy -0.2794 0.9906)
			)
			(stroke
				(width 0)
				(type default)
			)
			(fill no)
			(layer "F.CrtYd")
		)
		(fp_line
			(start -0.2794 -0.1016)
			(end -0.2794 0.9906)
			(stroke
				(width 0.1)
				(type default)
			)
			(layer "F.Fab")
		)
		(fp_line
			(start -0.2794 0.9906)
			(end 0.2794 0.9906)
			(stroke
				(width 0.1)
				(type default)
			)
			(layer "F.Fab")
		)
		(fp_line
			(start 0.2794 -0.1016)
			(end -0.2794 -0.1016)
			(stroke
				(width 0.1)
				(type default)
			)
			(layer "F.Fab")
		)
		(fp_line
			(start 0.2794 0.9906)
			(end 0.2794 -0.1016)
			(stroke
				(width 0.1)
				(type default)
			)
			(layer "F.Fab")
		)
		(pad "1" smd rect
			(at 0 0)
			(size 0.508 0.508)
			(layers "F.Cu" "F.Mask" "F.Paste")
			(net "PCA9554_A2")
		)
		(pad "2" smd rect
			(at 0 0.889)
			(size 0.508 0.508)
			(layers "F.Cu" "F.Mask" "F.Paste")
			(net "GND")
		)
		(zone
			(layer "F.Cu")
			(hatch none 0.5)
			(connect_pads
				(clearance 0)
			)
			(min_thickness 0.25)
			(keepout
				(tracks allowed)
				(vias not_allowed)
				(pads allowed)
				(copperpour not_allowed)
				(footprints allowed)
			)
			(placement
				(enabled no)
				(sheetname "")
			)
			(fill
				(thermal_gap 0.5)
				(thermal_bridge_width 0.5)
				(island_removal_mode 0)
			)
			(polygon
				(pts
					(xy 432.816 -14.859) (xy 433.324 -14.859) (xy 433.324 -14.478) (xy 432.816 -14.478)
				)
			)
		)
		(zone
			(layer "F.Cu")
			(hatch none 0.5)
			(connect_pads
				(clearance 0)
			)
			(min_thickness 0.25)
			(keepout
				(tracks not_allowed)
				(vias allowed)
				(pads allowed)
				(copperpour not_allowed)
				(footprints allowed)
			)
			(placement
				(enabled no)
				(sheetname "")
			)
			(fill
				(thermal_gap 0.5)
				(thermal_bridge_width 0.5)
				(island_removal_mode 0)
			)
			(polygon
				(pts
					(xy 432.816 -14.478) (xy 433.324 -14.478) (xy 433.324 -14.859) (xy 432.816 -14.859)
				)
			)
		)
	)
	(footprint ""
		(layer "F.Cu")
		(at 386.842 -87.3125 180)
		(property "Reference" "R7C14"
			(at 0 0 180)
			(layer "F.SilkS")
			(hide yes)
			(effects
				(font
					(size 1.27 1.27)
				)
			)
		)
		(property "Value" ""
			(at 0 0 180)
			(layer "F.Fab")
			(effects
				(font
					(size 1.27 1.27)
				)
			)
		)
		(duplicate_pad_numbers_are_jumpers no)
		(fp_poly
			(pts
				(xy -0.2794 -0.1016) (xy 0.2794 -0.1016) (xy 0.2794 0.9906) (xy -0.2794 0.9906)
			)
			(stroke
				(width 0)
				(type default)
			)
			(fill no)
			(layer "F.CrtYd")
		)
		(fp_line
			(start 0.2794 0.9906)
			(end 0.2794 -0.1016)
			(stroke
				(width 0.1)
				(type default)
			)
			(layer "F.Fab")
		)
		(fp_line
			(start 0.2794 -0.1016)
			(end -0.2794 -0.1016)
			(stroke
				(width 0.1)
				(type default)
			)
			(layer "F.Fab")
		)
		(fp_line
			(start -0.2794 0.9906)
			(end 0.2794 0.9906)
			(stroke
				(width 0.1)
				(type default)
			)
			(layer "F.Fab")
		)
		(fp_line
			(start -0.2794 -0.1016)
			(end -0.2794 0.9906)
			(stroke
				(width 0.1)
				(type default)
			)
			(layer "F.Fab")
		)
		(pad "1" smd rect
			(at 0 0 180)
			(size 0.508 0.508)
			(layers "F.Cu" "F.Mask" "F.Paste")
			(net "RMII_BMC_PCH_SPRNGVLLE_RXER")
		)
		(pad "2" smd rect
			(at 0 0.889 180)
			(size 0.508 0.508)
			(layers "F.Cu" "F.Mask" "F.Paste")
			(net "RMII_BMC_PCH_SPRNGVLLE_RXER_R")
		)
		(zone
			(layer "F.Cu")
			(hatch none 0.5)
			(connect_pads
				(clearance 0)
			)
			(min_thickness 0.25)
			(keepout
				(tracks not_allowed)
				(vias allowed)
				(pads allowed)
				(copperpour not_allowed)
				(footprints allowed)
			)
			(placement
				(enabled no)
				(sheetname "")
			)
			(fill
				(thermal_gap 0.5)
				(thermal_bridge_width 0.5)
				(island_removal_mode 0)
			)
			(polygon
				(pts
					(xy 387.096 -87.9475) (xy 386.588 -87.9475) (xy 386.588 -87.5665) (xy 387.096 -87.5665)
				)
			)
		)
		(zone
			(layer "F.Cu")
			(hatch none 0.5)
			(connect_pads
				(clearance 0)
			)
			(min_thickness 0.25)
			(keepout
				(tracks allowed)
				(vias not_allowed)
				(pads allowed)
				(copperpour not_allowed)
				(footprints allowed)
			)
			(placement
				(enabled no)
				(sheetname "")
			)
			(fill
				(thermal_gap 0.5)
				(thermal_bridge_width 0.5)
				(island_removal_mode 0)
			)
			(polygon
				(pts
					(xy 387.096 -87.5665) (xy 386.588 -87.5665) (xy 386.588 -87.9475) (xy 387.096 -87.9475)
				)
			)
		)
	)
	(footprint ""
		(layer "F.Cu")
		(at 166.624 -150.241 90)
		(property "Reference" "R4A3"
			(at 0 0 90)
			(layer "F.SilkS")
			(hide yes)
			(effects
				(font
					(size 1.27 1.27)
				)
			)
		)
		(property "Value" ""
			(at 0 0 90)
			(layer "F.Fab")
			(effects
				(font
					(size 1.27 1.27)
				)
			)
		)
		(duplicate_pad_numbers_are_jumpers no)
		(fp_poly
			(pts
				(xy -0.2794 -0.1016) (xy 0.2794 -0.1016) (xy 0.2794 0.9906) (xy -0.2794 0.9906)
			)
			(stroke
				(width 0)
				(type default)
			)
			(fill no)
			(layer "F.CrtYd")
		)
		(fp_line
			(start 0.2794 -0.1016)
			(end -0.2794 -0.1016)
			(stroke
				(width 0.1)
				(type default)
			)
			(layer "F.Fab")
		)
		(fp_line
			(start -0.2794 -0.1016)
			(end -0.2794 0.9906)
			(stroke
				(width 0.1)
				(type default)
			)
			(layer "F.Fab")
		)
		(fp_line
			(start 0.2794 0.9906)
			(end 0.2794 -0.1016)
			(stroke
				(width 0.1)
				(type default)
			)
			(layer "F.Fab")
		)
		(fp_line
			(start -0.2794 0.9906)
			(end 0.2794 0.9906)
			(stroke
				(width 0.1)
				(type default)
			)
			(layer "F.Fab")
		)
		(pad "1" smd rect
			(at 0 0 90)
			(size 0.508 0.508)
			(layers "F.Cu" "F.Mask" "F.Paste")
			(net "PWRGD_PVDDQ_KLM_R")
		)
		(pad "2" smd rect
			(at 0 0.889 90)
			(size 0.508 0.508)
			(layers "F.Cu" "F.Mask" "F.Paste")
			(net "FM_PVTT_KLM_EN_R")
		)
		(zone
			(layer "F.Cu")
			(hatch none 0.5)
			(connect_pads
				(clearance 0)
			)
			(min_thickness 0.25)
			(keepout
				(tracks allowed)
				(vias not_allowed)
				(pads allowed)
				(copperpour not_allowed)
				(footprints allowed)
			)
			(placement
				(enabled no)
				(sheetname "")
			)
			(fill
				(thermal_gap 0.5)
				(thermal_bridge_width 0.5)
				(island_removal_mode 0)
			)
			(polygon
				(pts
					(xy 166.878 -149.987) (xy 166.878 -150.495) (xy 167.259 -150.495) (xy 167.259 -149.987)
				)
			)
		)
		(zone
			(layer "F.Cu")
			(hatch none 0.5)
			(connect_pads
				(clearance 0)
			)
			(min_thickness 0.25)
			(keepout
				(tracks not_allowed)
				(vias allowed)
				(pads allowed)
				(copperpour not_allowed)
				(footprints allowed)
			)
			(placement
				(enabled no)
				(sheetname "")
			)
			(fill
				(thermal_gap 0.5)
				(thermal_bridge_width 0.5)
				(island_removal_mode 0)
			)
			(polygon
				(pts
					(xy 167.259 -149.987) (xy 167.259 -150.495) (xy 166.878 -150.495) (xy 166.878 -149.987)
				)
			)
		)
	)
)
